# SCM (Grand Teton) — schematic netlist excerpt (pin names and nets, part order shuffled) for the footprints in the layout excerpt that follows; sources: Cadence DE-HDL packaged netlist, KiCad conversion of 12092022_DA0F0TMDCD0_F0T_Management_Board_D_brd_V3_OCP.brd

C294  Q_CAP  0.1UF 25V 10% X7R  pkg 0402  page 54 : A = P1V8_AUX ; B = GND
R11  Q_RES  4.7K 1% CHIP  pkg 0402LF  page 21 : A = P3V3_AUX ; B = BMC_EMMC_RST_N

(kicad_pcb
	(version 20260206)
	(generator "pcbnew")
	(generator_version "10.0")
	(general
		(thickness 1.6)
		(legacy_teardrops no)
	)
	(paper "A4")
	(title_block
		(title "12092022_DA0F0TMDCD0_F0T_Management_Board_D_brd_V3_OCP.brd")
		(comment 1 "Grand Teton / footprints 406-407 of 1440")
	)
	(layers
		(0 "F.Cu" signal "TOP")
		(4 "In1.Cu" signal "GND")
		(6 "In2.Cu" signal "IN1")
		(8 "In3.Cu" signal "GND1")
		(10 "In4.Cu" signal "IN2")
		(12 "In5.Cu" signal "VCC")
		(14 "In6.Cu" signal "VCC1")
		(16 "In7.Cu" signal "IN3")
		(18 "In8.Cu" signal "GND2")
		(20 "In9.Cu" signal "IN4")
		(22 "In10.Cu" signal "GND3")
		(2 "B.Cu" signal "BOTTOM")
		(9 "F.Adhes" user "F.Adhesive")
		(11 "B.Adhes" user "B.Adhesive")
		(13 "F.Paste" user "Package Geometry/Pastemask Top")
		(15 "B.Paste" user "Package Geometry/Pastemask Bottom")
		(5 "F.SilkS" user "Ref Des/Silkscreen Top")
		(7 "B.SilkS" user "Ref Des/Silkscreen Bottom")
		(1 "F.Mask" user "Board Geometry/Soldermask Top")
		(3 "B.Mask" user "Board Geometry/Soldermask Bottom")
		(17 "Dwgs.User" user "User.Drawings")
		(19 "Cmts.User" user "User.Comments")
		(21 "Eco1.User" user "User.Eco1")
		(23 "Eco2.User" user "User.Eco2")
		(25 "Edge.Cuts" user "Board Geometry/Outline")
		(27 "Margin" user)
		(31 "F.CrtYd" user "Package Geometry/Place Bound Top")
		(29 "B.CrtYd" user "Package Geometry/Place Bound Bottom")
		(35 "F.Fab" user "Ref Des/Assembly Top")
		(33 "B.Fab" user "Ref Des/Assembly Bottom")
	)
	(footprint ""
		(layer "F.Cu")
		(at 40.222678 -53.992272)
		(property "Reference" "C294"
			(at 0 0 0)
			(layer "F.SilkS")
			(hide yes)
			(effects
				(font
					(size 1.27 1.27)
				)
			)
		)
		(property "Value" ""
			(at 0 0 0)
			(layer "F.Fab")
			(effects
				(font
					(size 1.27 1.27)
				)
			)
		)
		(duplicate_pad_numbers_are_jumpers no)
		(fp_line
			(start -0.7874 -0.4064)
			(end 0.7874 -0.4064)
			(stroke
				(width 0.1524)
				(type default)
			)
			(layer "F.SilkS")
		)
		(fp_line
			(start -0.7874 0.4064)
			(end -0.7874 -0.4064)
			(stroke
				(width 0.1524)
				(type default)
			)
			(layer "F.SilkS")
		)
		(fp_line
			(start 0.7874 -0.4064)
			(end 0.7874 0.4064)
			(stroke
				(width 0.1524)
				(type default)
			)
			(layer "F.SilkS")
		)
		(fp_line
			(start 0.7874 0.4064)
			(end -0.7874 0.4064)
			(stroke
				(width 0.1524)
				(type default)
			)
			(layer "F.SilkS")
		)
		(fp_line
			(start -0.67945 -0.305054)
			(end -0.12065 -0.305054)
			(stroke
				(width 0.1)
				(type default)
			)
			(layer "F.Fab")
		)
		(fp_line
			(start -0.67945 0.3048)
			(end -0.67945 -0.305054)
			(stroke
				(width 0.1)
				(type default)
			)
			(layer "F.Fab")
		)
		(fp_line
			(start -0.12065 -0.305054)
			(end -0.12065 -0.2794)
			(stroke
				(width 0.1)
				(type default)
			)
			(layer "F.Fab")
		)
		(fp_line
			(start -0.12065 -0.2794)
			(end 0.12065 -0.2794)
			(stroke
				(width 0.1)
				(type default)
			)
			(layer "F.Fab")
		)
		(fp_line
			(start -0.12065 0.2794)
			(end -0.12065 0.3048)
			(stroke
				(width 0.1)
				(type default)
			)
			(layer "F.Fab")
		)
		(fp_line
			(start -0.12065 0.3048)
			(end -0.67945 0.3048)
			(stroke
				(width 0.1)
				(type default)
			)
			(layer "F.Fab")
		)
		(fp_line
			(start 0.120396 0.2794)
			(end -0.12065 0.2794)
			(stroke
				(width 0.1)
				(type default)
			)
			(layer "F.Fab")
		)
		(fp_line
			(start 0.120396 0.3048)
			(end 0.120396 0.2794)
			(stroke
				(width 0.1)
				(type default)
			)
			(layer "F.Fab")
		)
		(fp_line
			(start 0.12065 -0.3048)
			(end 0.67945 -0.3048)
			(stroke
				(width 0.1)
				(type default)
			)
			(layer "F.Fab")
		)
		(fp_line
			(start 0.12065 -0.2794)
			(end 0.12065 -0.3048)
			(stroke
				(width 0.1)
				(type default)
			)
			(layer "F.Fab")
		)
		(fp_line
			(start 0.67945 -0.3048)
			(end 0.67945 0.3048)
			(stroke
				(width 0.1)
				(type default)
			)
			(layer "F.Fab")
		)
		(fp_line
			(start 0.67945 0.3048)
			(end 0.120396 0.3048)
			(stroke
				(width 0.1)
				(type default)
			)
			(layer "F.Fab")
		)
		(pad "1" smd circle
			(at -0.40005 0)
			(size 0 0)
			(layers "F.Cu" "F.Mask" "F.Paste")
			(net "P1V8_AUX")
		)
		(pad "2" smd circle
			(at 0.40005 0)
			(size 0 0)
			(layers "F.Cu" "F.Mask" "F.Paste")
			(net "GND")
		)
	)
	(footprint ""
		(layer "F.Cu")
		(at 33.782 -68.453 90)
		(property "Reference" "R11"
			(at 0 0 90)
			(layer "F.SilkS")
			(hide yes)
			(effects
				(font
					(size 1.27 1.27)
				)
			)
		)
		(property "Value" ""
			(at 0 0 90)
			(layer "F.Fab")
			(effects
				(font
					(size 1.27 1.27)
				)
			)
		)
		(duplicate_pad_numbers_are_jumpers no)
		(fp_line
			(start 0.7874 -0.4064)
			(end 0.7874 0.4064)
			(stroke
				(width 0.1524)
				(type default)
			)
			(layer "F.SilkS")
		)
		(fp_line
			(start -0.7874 -0.4064)
			(end 0.7874 -0.4064)
			(stroke
				(width 0.1524)
				(type default)
			)
			(layer "F.SilkS")
		)
		(fp_line
			(start 0.7874 0.4064)
			(end -0.7874 0.4064)
			(stroke
				(width 0.1524)
				(type default)
			)
			(layer "F.SilkS")
		)
		(fp_line
			(start -0.7874 0.4064)
			(end -0.7874 -0.4064)
			(stroke
				(width 0.1524)
				(type default)
			)
			(layer "F.SilkS")
		)
		(fp_line
			(start -0.12065 -0.305054)
			(end -0.12065 -0.2794)
			(stroke
				(width 0.1)
				(type default)
			)
			(layer "F.Fab")
		)
		(fp_line
			(start -0.67945 -0.305054)
			(end -0.12065 -0.305054)
			(stroke
				(width 0.1)
				(type default)
			)
			(layer "F.Fab")
		)
		(fp_line
			(start 0.67945 -0.3048)
			(end 0.67945 0.3048)
			(stroke
				(width 0.1)
				(type default)
			)
			(layer "F.Fab")
		)
		(fp_line
			(start 0.12065 -0.3048)
			(end 0.67945 -0.3048)
			(stroke
				(width 0.1)
				(type default)
			)
			(layer "F.Fab")
		)
		(fp_line
			(start 0.12065 -0.2794)
			(end 0.12065 -0.3048)
			(stroke
				(width 0.1)
				(type default)
			)
			(layer "F.Fab")
		)
		(fp_line
			(start -0.12065 -0.2794)
			(end 0.12065 -0.2794)
			(stroke
				(width 0.1)
				(type default)
			)
			(layer "F.Fab")
		)
		(fp_line
			(start 0.120396 0.2794)
			(end -0.12065 0.2794)
			(stroke
				(width 0.1)
				(type default)
			)
			(layer "F.Fab")
		)
		(fp_line
			(start -0.12065 0.2794)
			(end -0.12065 0.3048)
			(stroke
				(width 0.1)
				(type default)
			)
			(layer "F.Fab")
		)
		(fp_line
			(start 0.67945 0.3048)
			(end 0.120396 0.3048)
			(stroke
				(width 0.1)
				(type default)
			)
			(layer "F.Fab")
		)
		(fp_line
			(start 0.120396 0.3048)
			(end 0.120396 0.2794)
			(stroke
				(width 0.1)
				(type default)
			)
			(layer "F.Fab")
		)
		(fp_line
			(start -0.12065 0.3048)
			(end -0.67945 0.3048)
			(stroke
				(width 0.1)
				(type default)
			)
			(layer "F.Fab")
		)
		(fp_line
			(start -0.67945 0.3048)
			(end -0.67945 -0.305054)
			(stroke
				(width 0.1)
				(type default)
			)
			(layer "F.Fab")
		)
		(pad "1" smd circle
			(at -0.40005 0 90)
			(size 0 0)
			(layers "F.Cu" "F.Mask" "F.Paste")
			(net "P3V3_AUX")
		)
		(pad "2" smd circle
			(at 0.40005 0 90)
			(size 0 0)
			(layers "F.Cu" "F.Mask" "F.Paste")
			(net "BMC_EMMC_RST_N")
		)
	)
)
